FILE_TYPE = CONNECTIVITY;
{Allegro Design Entry HDL 16.6-p007 (v16-6-112F) 10/10/2012}
"PAGE_NUMBER" = 131;
0"NC";
1"GND\g";
2"P1V05_PCH_STBY\g";
3"P1V05_PCH_STBY\g";
4"GND\g";
5"P1V05_PCH_STBY\g";
6"GND\g";
7"P1V05_PCH_STBY\g";
8"GND\g";
9"GND\g";
10"P1V05_PCH_STBY\g";
11"GND\g";
12"P1V05_PCH_STBY\g";
13"P1V05_PCH_STBY\g";
14"P1V05_PCH_STBY\g";
15"GND\g";
16"GND\g";
%"CAP_A"
"1","(975,4975)","0","dev_discrete","I1";
;
LOCATION"C7B15"
PART_NUMBER"E15431-004"
VALUE"22.0UF"
TOLERANCE"20%"
PACK_TYPE"0603V"
VOLTAGE"4V"
MATERIAL"X6S"
CDS_LOCATION"C7B15"
BOM_COST"SB"
CDS_LIB"dev_discrete"
CDS_SEC"1"
$SEC"1"
ROOM"SB_DECOUPLING";
"B"
$PN"2"16;
"A"
$PN"1"14;
%"CAP_A"
"1","(500,4025)","0","dev_discrete","I10";
;
LOCATION"C7B22"
PART_NUMBER"E15431-004"
VALUE"22.0UF"
TOLERANCE"20%"
PACK_TYPE"0603V"
VOLTAGE"4V"
MATERIAL"X6S"
CDS_LOCATION"C7B22"
BOM_COST"SB"
CDS_LIB"dev_discrete"
CDS_SEC"1"
$SEC"1"
ROOM"SB_DECOUPLING";
"B"
$PN"2"1;
"A"
$PN"1"2;
%"CAP_A"
"1","(50,4025)","0","dev_discrete","I11";
;
LOCATION"C7B24"
PART_NUMBER"E15431-004"
VALUE"22.0UF"
TOLERANCE"20%"
PACK_TYPE"0603V"
VOLTAGE"4V"
MATERIAL"X6S"
CDS_LOCATION"C7B24"
BOM_COST"SB"
CDS_LIB"dev_discrete"
CDS_SEC"1"
$SEC"1"
ROOM"SB_DECOUPLING";
"B"
$PN"2"1;
"A"
$PN"1"2;
%"CAP_A"
"1","(-425,4025)","0","dev_discrete","I12";
;
LOCATION"C7B18"
PART_NUMBER"E15431-004"
VALUE"22.0UF"
TOLERANCE"20%"
PACK_TYPE"0603V"
VOLTAGE"4V"
MATERIAL"X6S"
CDS_LOCATION"C7B18"
BOM_COST"SB"
CDS_LIB"dev_discrete"
CDS_SEC"1"
$SEC"1"
ROOM"SB_DECOUPLING";
"B"
$PN"2"1;
"A"
$PN"1"2;
%"GND"
"1","(275,3650)","0","mstr_symbols","I13";
;
VOLTAGE"0"
SIZE"1B"
CDS_LIB"mstr_symbols"
BOM_COST"SB"
ROOM"SB_DECOUPLING"
BODY_TYPE"PLUMBING"
HDL_POWER"GND";
"A\NAC"1;
%"CAP_A"
"1","(500,3025)","0","dev_discrete","I14";
;
LOCATION"C8B9"
PART_NUMBER"E15431-004"
VALUE"22.0UF"
PACK_TYPE"0603V"
VOLTAGE"4V"
MATERIAL"X6S"
TOLERANCE"20%"
CDS_LOCATION"C8B9"
BOM_COST"SB"
CDS_LIB"dev_discrete"
CDS_SEC"1"
$SEC"1"
ROOM"SB_DECOUPLING";
"B"
$PN"2"4;
"A"
$PN"1"3;
%"CAP_A"
"1","(50,3025)","0","dev_discrete","I15";
;
LOCATION"C8B11"
PART_NUMBER"E15431-004"
VALUE"22.0UF"
TOLERANCE"20%"
PACK_TYPE"0603V"
VOLTAGE"4V"
MATERIAL"X6S"
CDS_LOCATION"C8B11"
BOM_COST"SB"
CDS_LIB"dev_discrete"
CDS_SEC"1"
$SEC"1"
ROOM"SB_DECOUPLING";
"B"
$PN"2"4;
"A"
$PN"1"3;
%"CAP_A"
"1","(-400,3025)","0","dev_discrete","I16";
;
LOCATION"C8B14"
PART_NUMBER"E15431-004"
VALUE"22.0UF"
TOLERANCE"20%"
PACK_TYPE"0603V"
VOLTAGE"4V"
MATERIAL"X6S"
CDS_LOCATION"C8B14"
BOM_COST"SB"
CDS_LIB"dev_discrete"
CDS_SEC"1"
$SEC"1"
ROOM"SB_DECOUPLING";
"B"
$PN"2"4;
"A"
$PN"1"3;
%"P1V05_PCH_STBY"
"1","(-625,4300)","0","mstr_symbols","I17";
;
VOLTAGE"1.05V"
BOM_COST"SB"
CDS_LIB"mstr_symbols"
ROOM"SB_DECOUPLING"
BODY_TYPE"PLUMBING"
HDL_POWER"P1V05_PCH_STBY";
"G\NAC"2;
%"CAP_A"
"1","(-875,4025)","0","dev_discrete","I18";
;
LOCATION"C7B17"
PART_NUMBER"E15431-004"
VALUE"22.0UF"
TOLERANCE"20%"
PACK_TYPE"0603V"
VOLTAGE"4V"
MATERIAL"X6S"
CDS_LOCATION"C7B17"
BOM_COST"SB"
CDS_LIB"dev_discrete"
CDS_SEC"1"
$SEC"1"
ROOM"SB_DECOUPLING";
"B"
$PN"2"1;
"A"
$PN"1"2;
%"P1V05_PCH_STBY"
"1","(-625,3325)","0","mstr_symbols","I19";
;
VOLTAGE"1.05V"
BOM_COST"SB"
CDS_LIB"mstr_symbols"
ROOM"SB_DECOUPLING"
BODY_TYPE"PLUMBING"
HDL_POWER"P1V05_PCH_STBY";
"G\NAC"3;
%"CAP_A"
"1","(500,4975)","0","dev_discrete","I2";
;
LOCATION"C7B19"
PART_NUMBER"E15431-004"
VALUE"22.0UF"
TOLERANCE"20%"
PACK_TYPE"0603V"
VOLTAGE"4V"
MATERIAL"X6S"
CDS_LOCATION"C7B19"
BOM_COST"SB"
CDS_LIB"dev_discrete"
CDS_SEC"1"
$SEC"1"
ROOM"SB_DECOUPLING";
"B"
$PN"2"16;
"A"
$PN"1"14;
%"CAP_A"
"1","(-850,3025)","0","dev_discrete","I20";
;
LOCATION"C8B13"
PART_NUMBER"E15431-004"
VALUE"22.0UF"
TOLERANCE"20%"
PACK_TYPE"0603V"
VOLTAGE"4V"
MATERIAL"X6S"
CDS_LOCATION"C8B13"
BOM_COST"SB"
CDS_LIB"dev_discrete"
CDS_SEC"1"
$SEC"1"
ROOM"SB_DECOUPLING";
"B"
$PN"2"4;
"A"
$PN"1"3;
%"GND"
"1","(275,2675)","0","mstr_symbols","I21";
;
VOLTAGE"0.0V"
SIZE"1B"
CDS_LIB"mstr_symbols"
BOM_COST"SB"
ROOM"SB_DECOUPLING"
BODY_TYPE"PLUMBING"
HDL_POWER"GND";
"A\NAC"4;
%"CAP"
"1","(50,2025)","0","mstr_discrete","I22";
;
LOCATION"C8B16"
PART_NUMBER"C95333-006"
VALUE"47UF"
TOLERANCE"20%"
PACK_TYPE"0805"
VOLTAGE"4V"
MATERIAL"X6S"
BOM_COST"SB"
CDS_LIB"mstr_discrete"
CDS_SEC"1"
$SEC"1"
CDS_LOCATION"C8B16"
ROOM"SB_DECOUPLING";
"A"
$PN"1"5;
"B"
$PN"2"6;
%"P1V05_PCH_STBY"
"1","(-175,2325)","0","mstr_symbols","I23";
;
VOLTAGE"1.05V"
BOM_COST"SB"
CDS_LIB"mstr_symbols"
ROOM"SB_DECOUPLING"
BODY_TYPE"PLUMBING"
HDL_POWER"P1V05_PCH_STBY";
"G\NAC"5;
%"CAP"
"1","(-400,2025)","0","mstr_discrete","I24";
;
LOCATION"C8B15"
PART_NUMBER"C95333-006"
VALUE"47UF"
TOLERANCE"20%"
PACK_TYPE"0805"
VOLTAGE"4V"
MATERIAL"X6S"
BOM_COST"SB"
CDS_LIB"mstr_discrete"
CDS_SEC"1"
$SEC"1"
CDS_LOCATION"C8B15"
ROOM"SB_DECOUPLING";
"A"
$PN"1"5;
"B"
$PN"2"6;
%"GND"
"1","(-175,1650)","0","mstr_symbols","I25";
;
VOLTAGE"0.0V"
SIZE"1B"
CDS_LIB"mstr_symbols"
BOM_COST"SB"
ROOM"SB_DECOUPLING"
BODY_TYPE"PLUMBING"
HDL_POWER"GND";
"A\NAC"6;
%"P1V05_PCH_STBY"
"1","(-4575,5000)","0","mstr_symbols","I26";
;
VOLTAGE"1.05V"
BOM_COST"SB"
CDS_LIB"mstr_symbols"
ROOM"SB_DECOUPLING"
BODY_TYPE"PLUMBING"
HDL_POWER"P1V05_PCH_STBY";
"G\NAC"7;
%"CAP_A"
"1","(-2375,4725)","0","dev_discrete","I27";
;
LOCATION"C2M22"
PART_NUMBER"D97712-004"
VALUE"1.0UF"
TOLERANCE"10%"
PACK_TYPE"0402V"
VOLTAGE"6.3V"
MATERIAL"X6S"
CDS_LOCATION"C2M22"
BOM_COST"SB"
CDS_LIB"dev_discrete"
CDS_SEC"1"
$SEC"1"
ROOM"SB_DECOUPLING";
"B"
$PN"2"8;
"A"
$PN"1"7;
%"CAP_A"
"1","(-2800,4725)","0","dev_discrete","I28";
;
LOCATION"C2M21"
PART_NUMBER"D97712-004"
VALUE"1.0UF"
TOLERANCE"10%"
PACK_TYPE"0402V"
VOLTAGE"6.3V"
MATERIAL"X6S"
CDS_LOCATION"C2M21"
BOM_COST"SB"
CDS_LIB"dev_discrete"
CDS_SEC"1"
$SEC"1"
ROOM"SB_DECOUPLING";
"B"
$PN"2"8;
"A"
$PN"1"7;
%"CAP_A"
"1","(-3175,4725)","0","dev_discrete","I29";
;
LOCATION"C2M18"
PART_NUMBER"D97712-004"
VALUE"1.0UF"
TOLERANCE"10%"
PACK_TYPE"0402V"
VOLTAGE"6.3V"
MATERIAL"X6S"
CDS_LOCATION"C2M18"
BOM_COST"SB"
CDS_LIB"dev_discrete"
CDS_SEC"1"
$SEC"1"
ROOM"SB_DECOUPLING";
"B"
$PN"2"8;
"A"
$PN"1"7;
%"CAP_A"
"1","(50,4975)","0","dev_discrete","I3";
;
LOCATION"C7B16"
PART_NUMBER"E15431-004"
TOLERANCE"20%"
PACK_TYPE"0603V"
VOLTAGE"4V"
MATERIAL"X6S"
VALUE"22.0UF"
CDS_LOCATION"C7B16"
BOM_COST"SB"
CDS_LIB"dev_discrete"
CDS_SEC"1"
$SEC"1"
ROOM"SB_DECOUPLING";
"B"
$PN"2"16;
"A"
$PN"1"14;
%"GND"
"1","(-3350,4375)","0","mstr_symbols","I30";
;
VOLTAGE"0"
BOM_COST"SB"
SIZE"1B"
CDS_LIB"mstr_symbols"
ROOM"SB_DECOUPLING"
BODY_TYPE"PLUMBING"
HDL_POWER"GND";
"A\NAC"8;
%"CAP_A"
"1","(-2850,3525)","0","dev_discrete","I31";
;
LOCATION"C2M19"
PART_NUMBER"D97712-004"
VALUE"1.0UF"
TOLERANCE"10%"
PACK_TYPE"0402V"
VOLTAGE"6.3V"
MATERIAL"X6S"
CDS_LOCATION"C2M19"
BOM_COST"SB"
CDS_LIB"dev_discrete"
CDS_SEC"1"
$SEC"1"
ROOM"SB_DECOUPLING";
"B"
$PN"2"9;
"A"
$PN"1"12;
%"CAP_A"
"1","(-3225,3525)","0","dev_discrete","I32";
;
LOCATION"C3M38"
PART_NUMBER"D97712-004"
VALUE"1.0UF"
TOLERANCE"10%"
PACK_TYPE"0402V"
VOLTAGE"6.3V"
MATERIAL"X6S"
CDS_LOCATION"C3M38"
BOM_COST"SB"
CDS_LIB"dev_discrete"
CDS_SEC"1"
$SEC"1"
ROOM"SB_DECOUPLING";
"B"
$PN"2"9;
"A"
$PN"1"12;
%"GND"
"1","(-3425,3175)","0","mstr_symbols","I33";
;
VOLTAGE"0"
SIZE"1B"
CDS_LIB"mstr_symbols"
BOM_COST"SB"
ROOM"SB_DECOUPLING"
BODY_TYPE"PLUMBING"
HDL_POWER"GND";
"A\NAC"9;
%"CAP"
"1","(-2400,2025)","0","mstr_discrete","I34";
;
LOCATION"C2M17"
PART_NUMBER"C95333-006"
VALUE"47UF"
TOLERANCE"20%"
PACK_TYPE"0805"
VOLTAGE"4V"
MATERIAL"X6S"
CDS_LIB"mstr_discrete"
BOM_COST"SB"
CDS_SEC"1"
$SEC"1"
CDS_LOCATION"C2M17"
ROOM"SB_DECOUPLING";
"A"
$PN"1"10;
"B"
$PN"2"11;
%"CAP"
"1","(-2800,2025)","0","mstr_discrete","I35";
;
LOCATION"C2M11"
PART_NUMBER"C95333-006"
VALUE"47UF"
TOLERANCE"20%"
PACK_TYPE"0805"
VOLTAGE"4V"
MATERIAL"X6S"
BOM_COST"SB"
CDS_LIB"mstr_discrete"
CDS_SEC"1"
$SEC"1"
CDS_LOCATION"C2M11"
ROOM"SB_DECOUPLING";
"A"
$PN"1"10;
"B"
$PN"2"11;
%"P1V05_PCH_STBY"
"1","(-3025,2325)","0","mstr_symbols","I36";
;
VOLTAGE"1.05V"
BOM_COST"SB"
CDS_LIB"mstr_symbols"
ROOM"SB_DECOUPLING"
BODY_TYPE"PLUMBING"
HDL_POWER"P1V05_PCH_STBY";
"G\NAC"10;
%"CAP"
"1","(-3250,2025)","0","mstr_discrete","I37";
;
LOCATION"C8A13"
PART_NUMBER"C95333-006"
VALUE"47UF"
TOLERANCE"20%"
PACK_TYPE"0805"
VOLTAGE"4V"
MATERIAL"X6S"
CDS_LIB"mstr_discrete"
BOM_COST"SB"
CDS_SEC"1"
$SEC"1"
CDS_LOCATION"C8A13"
ROOM"SB_DECOUPLING";
"A"
$PN"1"10;
"B"
$PN"2"11;
%"GND"
"1","(-3025,1650)","0","mstr_symbols","I38";
;
VOLTAGE"0.0V"
BOM_COST"SB"
CDS_LIB"mstr_symbols"
SIZE"1B"
ROOM"SB_DECOUPLING"
BODY_TYPE"PLUMBING"
HDL_POWER"GND";
"A\NAC"11;
%"CAP_A"
"1","(-3550,4725)","0","dev_discrete","I39";
;
LOCATION"C2M20"
PART_NUMBER"D97712-004"
VALUE"1.0UF"
TOLERANCE"10%"
VOLTAGE"6.3V"
MATERIAL"X6S"
PACK_TYPE"0402V"
CDS_LOCATION"C2M20"
BOM_COST"SB"
CDS_LIB"dev_discrete"
CDS_SEC"1"
$SEC"1"
ROOM"SB_DECOUPLING";
"B"
$PN"2"8;
"A"
$PN"1"7;
%"CAP_A"
"1","(-425,4975)","0","dev_discrete","I4";
;
LOCATION"C7B21"
PART_NUMBER"E15431-004"
VALUE"22.0UF"
TOLERANCE"20%"
PACK_TYPE"0603V"
VOLTAGE"4V"
MATERIAL"X6S"
CDS_LOCATION"C7B21"
BOM_COST"SB"
CDS_LIB"dev_discrete"
CDS_SEC"1"
$SEC"1"
ROOM"SB_DECOUPLING";
"B"
$PN"2"16;
"A"
$PN"1"14;
%"CAP_A"
"1","(-3950,4725)","0","dev_discrete","I40";
;
PART_NUMBER"D97712-004"
LOCATION"C2N13"
VALUE"1.0UF"
TOLERANCE"10%"
VOLTAGE"6.3V"
MATERIAL"X6S"
PACK_TYPE"0402V"
CDS_LOCATION"C2N13"
BOM_COST"SB"
CDS_LIB"dev_discrete"
CDS_SEC"1"
$SEC"1"
ROOM"SB_DECOUPLING";
"B"
$PN"2"8;
"A"
$PN"1"7;
%"CAP_A"
"1","(-4350,4725)","0","dev_discrete","I41";
;
LOCATION"C2N2"
VALUE"1.0UF"
TOLERANCE"10%"
PACK_TYPE"0402V"
VOLTAGE"6.3V"
MATERIAL"X6S"
PART_NUMBER"D97712-004"
CDS_LOCATION"C2N2"
BOM_COST"SB"
CDS_LIB"dev_discrete"
CDS_SEC"1"
$SEC"1"
ROOM"SB_DECOUPLING";
"B"
$PN"2"8;
"A"
$PN"1"7;
%"CAP_A"
"1","(-3600,3525)","0","dev_discrete","I42";
;
LOCATION"C3M43"
PART_NUMBER"D97712-004"
VALUE"1.0UF"
TOLERANCE"10%"
PACK_TYPE"0402V"
VOLTAGE"6.3V"
MATERIAL"X6S"
CDS_LOCATION"C3M43"
BOM_COST"SB"
CDS_LIB"dev_discrete"
CDS_SEC"1"
$SEC"1"
ROOM"SB_DECOUPLING";
"B"
$PN"2"9;
"A"
$PN"1"12;
%"CAP_A"
"1","(-4000,3525)","0","dev_discrete","I43";
;
LOCATION"C2N7"
PART_NUMBER"D97712-004"
VALUE"1.0UF"
TOLERANCE"10%"
PACK_TYPE"0402V"
VOLTAGE"6.3V"
MATERIAL"X6S"
CDS_LOCATION"C2N7"
BOM_COST"SB"
CDS_LIB"dev_discrete"
CDS_SEC"1"
$SEC"1"
ROOM"SB_DECOUPLING";
"B"
$PN"2"9;
"A"
$PN"1"12;
%"CAP_A"
"1","(-4375,3525)","0","dev_discrete","I44";
;
LOCATION"C3M39"
PART_NUMBER"D97712-004"
VALUE"1.0UF"
TOLERANCE"10%"
PACK_TYPE"0402V"
VOLTAGE"6.3V"
MATERIAL"X6S"
CDS_LOCATION"C3M39"
BOM_COST"SB"
CDS_LIB"dev_discrete"
CDS_SEC"1"
$SEC"1"
ROOM"SB_DECOUPLING";
"B"
$PN"2"9;
"A"
$PN"1"12;
%"CAP_A"
"1","(-4750,4725)","0","dev_discrete","I45";
;
VALUE"1.0UF"
PART_NUMBER"D97712-004"
TOLERANCE"10%"
PACK_TYPE"0402V"
MATERIAL"X6S"
LOCATION"C3M42"
VOLTAGE"6.3V"
CDS_LOCATION"C3M42"
BOM_COST"SB"
CDS_LIB"dev_discrete"
CDS_SEC"1"
$SEC"1"
ROOM"SB_DECOUPLING";
"B"
$PN"2"8;
"A"
$PN"1"7;
%"P1V05_PCH_STBY"
"1","(-4600,3775)","0","mstr_symbols","I46";
;
VOLTAGE"1.05V"
BOM_COST"SB"
CDS_LIB"mstr_symbols"
ROOM"SB_DECOUPLING"
BODY_TYPE"PLUMBING"
HDL_POWER"P1V05_PCH_STBY";
"G\NAC"12;
%"CAP_A"
"1","(-4775,3525)","0","dev_discrete","I47";
;
LOCATION"C2N8"
PART_NUMBER"D97712-004"
VALUE"1.0UF"
TOLERANCE"10%"
PACK_TYPE"0402V"
VOLTAGE"6.3V"
MATERIAL"X6S"
CDS_LOCATION"C2N8"
BOM_COST"SB"
CDS_LIB"dev_discrete"
CDS_SEC"1"
$SEC"1"
ROOM"SB_DECOUPLING";
"B"
$PN"2"9;
"A"
$PN"1"12;
%"CAP_A"
"1","(-4250,2100)","0","dev_discrete","I48";
;
LOCATION"C2M13"
PART_NUMBER"E15431-004"
VALUE"22.0UF"
TOLERANCE"20%"
PACK_TYPE"0603V"
VOLTAGE"4V"
MATERIAL"X6S"
CDS_LOCATION"C2M13"
BOM_COST"SB"
CDS_LIB"dev_discrete"
CDS_SEC"1"
$SEC"1"
ROOM"SB_DECOUPLING";
"B"
$PN"2"15;
"A"
$PN"1"13;
%"P1V05_PCH_STBY"
"1","(-4800,2400)","0","mstr_symbols","I49";
;
VOLTAGE"1.05V"
BOM_COST"SB"
CDS_LIB"mstr_symbols"
ROOM"SB_DECOUPLING"
BODY_TYPE"PLUMBING"
HDL_POWER"P1V05_PCH_STBY";
"G\NAC"13;
%"P1V05_PCH_STBY"
"1","(-600,5225)","0","mstr_symbols","I5";
;
VOLTAGE"1.05V"
BOM_COST"SB"
CDS_LIB"mstr_symbols"
ROOM"SB_DECOUPLING"
BODY_TYPE"PLUMBING"
HDL_POWER"P1V05_PCH_STBY";
"G\NAC"14;
%"CAP_A"
"1","(-4650,2100)","0","dev_discrete","I50";
;
LOCATION"C2N10"
PART_NUMBER"E15431-004"
VALUE"22.0UF"
TOLERANCE"20%"
PACK_TYPE"0603V"
VOLTAGE"4V"
MATERIAL"X6S"
CDS_LOCATION"C2N10"
BOM_COST"SB"
CDS_LIB"dev_discrete"
CDS_SEC"1"
$SEC"1"
ROOM"SB_DECOUPLING";
"B"
$PN"2"15;
"A"
$PN"1"13;
%"GND"
"1","(-4800,1725)","0","mstr_symbols","I51";
;
VOLTAGE"0.0V"
CDS_LIB"mstr_symbols"
SIZE"1B"
BOM_COST"SB"
ROOM"SB_DECOUPLING"
BODY_TYPE"PLUMBING"
HDL_POWER"GND";
"A\NAC"15;
%"CAP_A"
"1","(-5075,2100)","0","dev_discrete","I52";
;
LOCATION"C2M12"
PART_NUMBER"E15431-004"
VALUE"22.0UF"
TOLERANCE"20%"
PACK_TYPE"0603V"
VOLTAGE"4V"
MATERIAL"X6S"
CDS_LOCATION"C2M12"
BOM_COST"SB"
CDS_LIB"dev_discrete"
CDS_SEC"1"
$SEC"1"
ROOM"SB_DECOUPLING";
"B"
$PN"2"15;
"A"
$PN"1"13;
%"CAP_A"
"1","(-875,4975)","0","dev_discrete","I6";
;
LOCATION"C7B20"
PART_NUMBER"E15431-004"
TOLERANCE"20%"
PACK_TYPE"0603V"
VOLTAGE"4V"
MATERIAL"X6S"
VALUE"22.0UF"
CDS_LOCATION"C7B20"
BOM_COST"SB"
CDS_LIB"dev_discrete"
CDS_SEC"1"
$SEC"1"
ROOM"SB_DECOUPLING";
"B"
$PN"2"16;
"A"
$PN"1"14;
%"CAP_A"
"1","(975,4025)","0","dev_discrete","I7";
;
LOCATION"C7B23"
PART_NUMBER"E15431-004"
VALUE"22.0UF"
TOLERANCE"20%"
PACK_TYPE"0603V"
VOLTAGE"4V"
MATERIAL"X6S"
CDS_LOCATION"C7B23"
BOM_COST"SB"
CDS_LIB"dev_discrete"
CDS_SEC"1"
$SEC"1"
ROOM"SB_DECOUPLING";
"B"
$PN"2"1;
"A"
$PN"1"2;
%"CAP_A"
"1","(950,3025)","0","dev_discrete","I8";
;
LOCATION"C8B10"
PART_NUMBER"E15431-004"
VALUE"22.0UF"
TOLERANCE"20%"
PACK_TYPE"0603V"
VOLTAGE"4V"
MATERIAL"X6S"
CDS_LOCATION"C8B10"
BOM_COST"SB"
CDS_LIB"dev_discrete"
CDS_SEC"1"
$SEC"1"
ROOM"SB_DECOUPLING";
"B"
$PN"2"4;
"A"
$PN"1"3;
%"GND"
"1","(275,4625)","0","mstr_symbols","I9";
;
VOLTAGE"0"
SIZE"1B"
CDS_LIB"mstr_symbols"
BOM_COST"SB"
ROOM"SB_DECOUPLING"
BODY_TYPE"PLUMBING"
HDL_POWER"GND";
"A\NAC"16;
END.
